# T6G (Grand Teton) — schematic netlist excerpt (pin names and nets, part order shuffled) for the footprints in the layout excerpt that follows; sources: Cadence DE-HDL packaged netlist, KiCad conversion of 04192023_DAF0TMB3IC0_F0TG_MB_C_brd_V02_OCP.brd

C385  Q_CAP  0.1UF 10V 10% X7S  pkg C0201  page 345 : A = P0V9_CPU1_RT_2D ; B = GND
C2038  Q_CAP  10UF 6.3V 20% X6S  pkg C0402  page 234 : A = P3V3_AUX_USB_HUB ; B = GND
C670  Q_CAP  4.7UF 6.3V 20% X6S  pkg 0402  page 301 : A = P1V8_CPU0_RT2_1A ; B = GND

(kicad_pcb
	(version 20260206)
	(generator "pcbnew")
	(generator_version "10.0")
	(general
		(thickness 1.6)
		(legacy_teardrops no)
	)
	(paper "A4")
	(title_block
		(title "04192023_DAF0TMB3IC0_F0TG_MB_C_brd_V02_OCP.brd")
		(comment 1 "Grand Teton / footprints 6358-6360 of 8354")
	)
	(layers
		(0 "F.Cu" signal "TOP")
		(4 "In1.Cu" signal "GND")
		(6 "In2.Cu" signal "IN1")
		(8 "In3.Cu" signal "GND1")
		(10 "In4.Cu" signal "IN2")
		(12 "In5.Cu" signal "GND2")
		(14 "In6.Cu" signal "IN3")
		(16 "In7.Cu" signal "GND3")
		(18 "In8.Cu" signal "VCC")
		(20 "In9.Cu" signal "VCC1")
		(22 "In10.Cu" signal "GND4")
		(24 "In11.Cu" signal "IN4")
		(26 "In12.Cu" signal "GND5")
		(28 "In13.Cu" signal "IN5")
		(30 "In14.Cu" signal "GND6")
		(32 "In15.Cu" signal "IN6")
		(34 "In16.Cu" signal "GND7")
		(2 "B.Cu" signal "BOTTOM")
		(9 "F.Adhes" user "F.Adhesive")
		(11 "B.Adhes" user "B.Adhesive")
		(13 "F.Paste" user "Package Geometry/Pastemask Top")
		(15 "B.Paste" user "Package Geometry/Pastemask Bottom")
		(5 "F.SilkS" user "Ref Des/Silkscreen Top")
		(7 "B.SilkS" user "Ref Des/Silkscreen Bottom")
		(1 "F.Mask" user "Board Geometry/Soldermask Top")
		(3 "B.Mask" user "Board Geometry/Soldermask Bottom")
		(17 "Dwgs.User" user "User.Drawings")
		(19 "Cmts.User" user "User.Comments")
		(21 "Eco1.User" user "User.Eco1")
		(23 "Eco2.User" user "User.Eco2")
		(25 "Edge.Cuts" user "Board Geometry/Outline")
		(27 "Margin" user)
		(31 "F.CrtYd" user "Package Geometry/Place Bound Top")
		(29 "B.CrtYd" user "Package Geometry/Place Bound Bottom")
		(35 "F.Fab" user "Ref Des/Assembly Top")
		(33 "B.Fab" user "Ref Des/Assembly Bottom")
	)
	(footprint ""
		(layer "B.Cu")
		(at 16.207994 -99.842066)
		(property "Reference" "C2038"
			(at 0 0 0)
			(layer "B.SilkS")
			(hide yes)
			(effects
				(font
					(size 1.27 1.27)
				)
				(justify mirror)
			)
		)
		(property "Value" ""
			(at 0 0 0)
			(layer "B.Fab")
			(effects
				(font
					(size 1.27 1.27)
				)
				(justify mirror)
			)
		)
		(duplicate_pad_numbers_are_jumpers no)
		(fp_line
			(start -0.7874 -0.4064)
			(end -0.7874 0.4064)
			(stroke
				(width 0.1524)
				(type default)
			)
			(layer "B.SilkS")
		)
		(fp_line
			(start -0.7874 0.4064)
			(end 0.7874 0.4064)
			(stroke
				(width 0.1524)
				(type default)
			)
			(layer "B.SilkS")
		)
		(fp_line
			(start 0.7874 -0.4064)
			(end -0.7874 -0.4064)
			(stroke
				(width 0.1524)
				(type default)
			)
			(layer "B.SilkS")
		)
		(fp_line
			(start 0.7874 0.4064)
			(end 0.7874 -0.4064)
			(stroke
				(width 0.1524)
				(type default)
			)
			(layer "B.SilkS")
		)
		(fp_line
			(start -0.67945 -0.3048)
			(end -0.67945 0.3048)
			(stroke
				(width 0.1)
				(type default)
			)
			(layer "B.Fab")
		)
		(fp_line
			(start -0.67945 0.3048)
			(end -0.120396 0.3048)
			(stroke
				(width 0.1)
				(type default)
			)
			(layer "B.Fab")
		)
		(fp_line
			(start -0.12065 -0.3048)
			(end -0.67945 -0.3048)
			(stroke
				(width 0.1)
				(type default)
			)
			(layer "B.Fab")
		)
		(fp_line
			(start -0.12065 -0.2794)
			(end -0.12065 -0.3048)
			(stroke
				(width 0.1)
				(type default)
			)
			(layer "B.Fab")
		)
		(fp_line
			(start -0.120396 0.2794)
			(end 0.12065 0.2794)
			(stroke
				(width 0.1)
				(type default)
			)
			(layer "B.Fab")
		)
		(fp_line
			(start -0.120396 0.3048)
			(end -0.120396 0.2794)
			(stroke
				(width 0.1)
				(type default)
			)
			(layer "B.Fab")
		)
		(fp_line
			(start 0.12065 -0.305054)
			(end 0.12065 -0.2794)
			(stroke
				(width 0.1)
				(type default)
			)
			(layer "B.Fab")
		)
		(fp_line
			(start 0.12065 -0.2794)
			(end -0.12065 -0.2794)
			(stroke
				(width 0.1)
				(type default)
			)
			(layer "B.Fab")
		)
		(fp_line
			(start 0.12065 0.2794)
			(end 0.12065 0.3048)
			(stroke
				(width 0.1)
				(type default)
			)
			(layer "B.Fab")
		)
		(fp_line
			(start 0.12065 0.3048)
			(end 0.67945 0.3048)
			(stroke
				(width 0.1)
				(type default)
			)
			(layer "B.Fab")
		)
		(fp_line
			(start 0.67945 -0.305054)
			(end 0.12065 -0.305054)
			(stroke
				(width 0.1)
				(type default)
			)
			(layer "B.Fab")
		)
		(fp_line
			(start 0.67945 0.3048)
			(end 0.67945 -0.305054)
			(stroke
				(width 0.1)
				(type default)
			)
			(layer "B.Fab")
		)
		(pad "1" smd circle
			(at 0.40005 0 180)
			(size 0 0)
			(layers "B.Cu" "B.Mask" "B.Paste")
			(net "P3V3_AUX_USB_HUB")
		)
		(pad "2" smd circle
			(at -0.40005 0 180)
			(size 0 0)
			(layers "B.Cu" "B.Mask" "B.Paste")
			(net "GND")
		)
	)
	(footprint ""
		(layer "B.Cu")
		(at 411.41904 -398.942052 90)
		(property "Reference" "C670"
			(at 0 0 90)
			(layer "B.SilkS")
			(hide yes)
			(effects
				(font
					(size 1.27 1.27)
				)
				(justify mirror)
			)
		)
		(property "Value" ""
			(at 0 0 90)
			(layer "B.Fab")
			(effects
				(font
					(size 1.27 1.27)
				)
				(justify mirror)
			)
		)
		(duplicate_pad_numbers_are_jumpers no)
		(fp_line
			(start 0.7874 -0.4064)
			(end -0.7874 -0.4064)
			(stroke
				(width 0.1524)
				(type default)
			)
			(layer "B.SilkS")
		)
		(fp_line
			(start -0.7874 -0.4064)
			(end -0.7874 0.4064)
			(stroke
				(width 0.1524)
				(type default)
			)
			(layer "B.SilkS")
		)
		(fp_line
			(start 0.7874 0.4064)
			(end 0.7874 -0.4064)
			(stroke
				(width 0.1524)
				(type default)
			)
			(layer "B.SilkS")
		)
		(fp_line
			(start -0.7874 0.4064)
			(end 0.7874 0.4064)
			(stroke
				(width 0.1524)
				(type default)
			)
			(layer "B.SilkS")
		)
		(fp_line
			(start 0.67945 -0.305054)
			(end 0.12065 -0.305054)
			(stroke
				(width 0.1)
				(type default)
			)
			(layer "B.Fab")
		)
		(fp_line
			(start 0.12065 -0.305054)
			(end 0.12065 -0.2794)
			(stroke
				(width 0.1)
				(type default)
			)
			(layer "B.Fab")
		)
		(fp_line
			(start -0.12065 -0.3048)
			(end -0.67945 -0.3048)
			(stroke
				(width 0.1)
				(type default)
			)
			(layer "B.Fab")
		)
		(fp_line
			(start -0.67945 -0.3048)
			(end -0.67945 0.3048)
			(stroke
				(width 0.1)
				(type default)
			)
			(layer "B.Fab")
		)
		(fp_line
			(start 0.12065 -0.2794)
			(end -0.12065 -0.2794)
			(stroke
				(width 0.1)
				(type default)
			)
			(layer "B.Fab")
		)
		(fp_line
			(start -0.12065 -0.2794)
			(end -0.12065 -0.3048)
			(stroke
				(width 0.1)
				(type default)
			)
			(layer "B.Fab")
		)
		(fp_line
			(start 0.12065 0.2794)
			(end 0.12065 0.3048)
			(stroke
				(width 0.1)
				(type default)
			)
			(layer "B.Fab")
		)
		(fp_line
			(start -0.120396 0.2794)
			(end 0.12065 0.2794)
			(stroke
				(width 0.1)
				(type default)
			)
			(layer "B.Fab")
		)
		(fp_line
			(start 0.67945 0.3048)
			(end 0.67945 -0.305054)
			(stroke
				(width 0.1)
				(type default)
			)
			(layer "B.Fab")
		)
		(fp_line
			(start 0.12065 0.3048)
			(end 0.67945 0.3048)
			(stroke
				(width 0.1)
				(type default)
			)
			(layer "B.Fab")
		)
		(fp_line
			(start -0.120396 0.3048)
			(end -0.120396 0.2794)
			(stroke
				(width 0.1)
				(type default)
			)
			(layer "B.Fab")
		)
		(fp_line
			(start -0.67945 0.3048)
			(end -0.120396 0.3048)
			(stroke
				(width 0.1)
				(type default)
			)
			(layer "B.Fab")
		)
		(pad "1" smd circle
			(at 0.40005 0 270)
			(size 0 0)
			(layers "B.Cu" "B.Mask" "B.Paste")
			(net "P1V8_CPU0_RT2_1A")
		)
		(pad "2" smd circle
			(at -0.40005 0 270)
			(size 0 0)
			(layers "B.Cu" "B.Mask" "B.Paste")
			(net "GND")
		)
	)
	(footprint ""
		(layer "B.Cu")
		(at 153.006298 -386.766562 90)
		(property "Reference" "C385"
			(at 0 0 90)
			(layer "B.SilkS")
			(hide yes)
			(effects
				(font
					(size 1.27 1.27)
				)
				(justify mirror)
			)
		)
		(property "Value" ""
			(at 0 0 90)
			(layer "B.Fab")
			(effects
				(font
					(size 1.27 1.27)
				)
				(justify mirror)
			)
		)
		(duplicate_pad_numbers_are_jumpers no)
		(fp_line
			(start 0.299974 -0.150114)
			(end -0.299974 -0.150114)
			(stroke
				(width 0.1)
				(type default)
			)
			(layer "B.Fab")
		)
		(fp_line
			(start -0.299974 -0.150114)
			(end -0.299974 0.150114)
			(stroke
				(width 0.1)
				(type default)
			)
			(layer "B.Fab")
		)
		(fp_line
			(start 0.299974 0.150114)
			(end 0.299974 -0.150114)
			(stroke
				(width 0.1)
				(type default)
			)
			(layer "B.Fab")
		)
		(fp_line
			(start -0.299974 0.150114)
			(end 0.299974 0.150114)
			(stroke
				(width 0.1)
				(type default)
			)
			(layer "B.Fab")
		)
		(pad "1" smd rect
			(at 0.2667 0 270)
			(size 0.3048 0.381)
			(layers "B.Cu" "B.Mask" "B.Paste")
			(net "P0V9_CPU1_RT_2D")
		)
		(pad "2" smd rect
			(at -0.2667 0 270)
			(size 0.3048 0.381)
			(layers "B.Cu" "B.Mask" "B.Paste")
			(net "GND")
		)
	)
)
